# S9S_MB_2U (Grand Teton) — schematic netlist excerpt (pin names and nets, part order shuffled) for the footprints in the layout excerpt that follows; sources: Cadence DE-HDL packaged netlist, KiCad conversion of 03242023_DA0F0TMBIJ0_F0T_Motherboard_J_brd_V01_OCP.brd

J35  SCONN168_ME1016810202011  IO  pkg CON_F168S2H7D_P0-6W2-95_LUH  page 159
  GND_A1  = GND
  GND_A2  = GND
  GND_A3  = GND
  GND_A4  = GND
  GND_A5  = GND
  GND_A6  = GND
  SMCLK  = SMB_OCP_V3_2_3V3AUX_BUF_R_SCL
  SMDAT  = SMB_OCP_V3_2_3V3AUX_BUF_R_SDA
  \smrst#\  = RST_SMB_OCP_V3_2_N
  \prsnta#\  = OCP_V3_1_PRSNTA_R_N
  \perst1#\  = RST_PERST1_OCP_V3_2_N
  \prsntb2#\  = OCP_V3_2_PRSNT2_R_N
  GND_A13  = GND
  REFCLKN1  = CLK_100M_OCP_V3_2_B_DN
  REFCLKP1  = CLK_100M_OCP_V3_2_B_DP
  GND_A16  = GND
  PERN0  = P5E_CPU1_PE1_RX_DN<0>
  PERP0  = P5E_CPU1_PE1_RX_DP<0>
  GND_A19  = GND
  PERN1  = P5E_CPU1_PE1_RX_DN<1>
  PERP1  = P5E_CPU1_PE1_RX_DP<1>
  GND_A22  = GND
  PERN2  = P5E_CPU1_PE1_RX_DN<2>
  PERP2  = P5E_CPU1_PE1_RX_DP<2>
  GND_A25  = GND
  PERN3  = P5E_CPU1_PE1_RX_DN<3>
  PERP3  = P5E_CPU1_PE1_RX_DP<3>
  GND_A28  = GND
  GND_A29  = GND
  PERN4  = P5E_CPU1_PE1_RX_DN<4>
  PERP4  = P5E_CPU1_PE1_RX_DP<4>
  GND_A32  = GND
  PERN5  = P5E_CPU1_PE1_RX_DN<5>
  PERP5  = P5E_CPU1_PE1_RX_DP<5>
  GND_A35  = GND
  PERN6  = P5E_CPU1_PE1_RX_DN<6>
  PERP6  = P5E_CPU1_PE1_RX_DP<6>
  GND_A38  = GND
  PERN7  = P5E_CPU1_PE1_RX_DN<7>
  PERP7  = P5E_CPU1_PE1_RX_DP<7>
  GND_A41  = GND
  \prsntb1#\  = OCP_V3_2_PRSNT1_R_N
  GND_A43  = GND
  PERN8  = P5E_CPU1_PE1_RX_DN<8>
  PERP8  = P5E_CPU1_PE1_RX_DP<8>
  GND_A46  = GND
  PERN9  = P5E_CPU1_PE1_RX_DN<9>
  PERP9  = P5E_CPU1_PE1_RX_DP<9>
  GND_A49  = GND
  PERN10  = P5E_CPU1_PE1_RX_DN<10>
  PERP10  = P5E_CPU1_PE1_RX_DP<10>
  GND_A52  = GND
  PERN11  = P5E_CPU1_PE1_RX_DN<11>
  PERP11  = P5E_CPU1_PE1_RX_DP<11>
  GND_A55  = GND
  PERN12  = P5E_CPU1_PE1_RX_DN<12>
  PERP12  = P5E_CPU1_PE1_RX_DP<12>
  GND_A58  = GND
  PERN13  = P5E_CPU1_PE1_RX_DN<13>
  PERP13  = P5E_CPU1_PE1_RX_DP<13>
  GND_A61  = GND
  PERN14  = P5E_CPU1_PE1_RX_DN<14>
  PERP14  = P5E_CPU1_PE1_RX_DP<14>
  GND_A64  = GND
  PERN15  = P5E_CPU1_PE1_RX_DN<15>
  PERP15  = P5E_CPU1_PE1_RX_DP<15>
  GND_A67  = GND
  USB_DATN  = USB2_5_R1_DN
  USB_DATP  = USB2_5_R1_DP
  \pwrbrk0#\  = OCP_V3_2_PWRBRK_N
  \+12v_edge_b1\  = P12V_OCP_V3_2
  \+12v_edge_b2\  = P12V_OCP_V3_2
  \+12v_edge_b3\  = P12V_OCP_V3_2
  \+12v_edge_b4\  = P12V_OCP_V3_2
  \+12v_edge_b5\  = P12V_OCP_V3_2
  \+12v_edge_b6\  = P12V_OCP_V3_2
  \bif0#\  = OCP_V3_2_BIF0_R_N
  \bif1#\  = OCP_V3_2_BIF1_R_N
  \bif2#\  = OCP_V3_2_BIF2_R_N
  \perst0#\  = RST_PERST0_OCP_V3_2_N
  \+3.3v_edge\  = P3V3_OCP_V3_2
  AUX_PWR_EN  = OCP_V3_2_AUX_PWR_EN_R
  GND_B13  = GND
  REFCLKN0  = CLK_100M_OCP_V3_2_A_DN
  REFCLKP0  = CLK_100M_OCP_V3_2_A_DP
  GND_B16  = GND
  PETN0  = P5E_CPU1_PE1_TX_C_DP<0>
  PETP0  = P5E_CPU1_PE1_TX_C_DN<0>
  GND_B19  = GND
  PETN1  = P5E_CPU1_PE1_TX_C_DN<1>
  PETP1  = P5E_CPU1_PE1_TX_C_DP<1>
  GND_B22  = GND
  PETN2  = P5E_CPU1_PE1_TX_C_DP<2>
  PETP2  = P5E_CPU1_PE1_TX_C_DN<2>
  GND_B25  = GND
  PETN3  = P5E_CPU1_PE1_TX_C_DN<3>
  PETP3  = P5E_CPU1_PE1_TX_C_DP<3>
  GND_B28  = GND
  GND_B29  = GND
  PETN4  = P5E_CPU1_PE1_TX_C_DP<4>
  PETP4  = P5E_CPU1_PE1_TX_C_DN<4>
  GND_B32  = GND
  PETN5  = P5E_CPU1_PE1_TX_C_DN<5>
  PETP5  = P5E_CPU1_PE1_TX_C_DP<5>
  GND_B35  = GND
  PETN6  = P5E_CPU1_PE1_TX_C_DP<6>
  PETP6  = P5E_CPU1_PE1_TX_C_DN<6>
  GND_B38  = GND
  PETN7  = P5E_CPU1_PE1_TX_C_DN<7>
  PETP7  = P5E_CPU1_PE1_TX_C_DP<7>
  GND_B41  = GND
  \prsntb0#\  = OCP_V3_2_PRSNT0_R_N
  GND_B43  = GND
  PETN8  = P5E_CPU1_PE1_TX_C_DP<8>
  PETP8  = P5E_CPU1_PE1_TX_C_DN<8>
  GND_B46  = GND
  PETN9  = P5E_CPU1_PE1_TX_C_DN<9>
  PETP9  = P5E_CPU1_PE1_TX_C_DP<9>
  GND_B49  = GND
  PETN10  = P5E_CPU1_PE1_TX_C_DP<10>
  PETP10  = P5E_CPU1_PE1_TX_C_DN<10>
  GND_B52  = GND
  PETN11  = P5E_CPU1_PE1_TX_C_DN<11>
  PETP11  = P5E_CPU1_PE1_TX_C_DP<11>
  GND_B55  = GND
  PETN12  = P5E_CPU1_PE1_TX_C_DP<12>
  PETP12  = P5E_CPU1_PE1_TX_C_DN<12>
  GND_B58  = GND
  PETN13  = P5E_CPU1_PE1_TX_C_DN<13>
  PETP13  = P5E_CPU1_PE1_TX_C_DP<13>
  GND_B61  = GND
  PETN14  = P5E_CPU1_PE1_TX_C_DP<14>
  PETP14  = P5E_CPU1_PE1_TX_C_DN<14>
  GND_B64  = GND
  PETN15  = P5E_CPU1_PE1_TX_C_DN<15>
  PETP15  = P5E_CPU1_PE1_TX_C_DP<15>
  GND_B67  = GND
  RFU1_NC_B68  = TP_OCP_V3_2_B68
  RFU1_NC_B69  = TP_OCP_V3_2_B69
  \prsntb3#\  = OCP_V3_2_PRSNT3_R_N
  G1  = GND
  G2  = GND
  G3  = GND
  G4  = GND
  G5  = GND
  \perst2#\  = RST_PERST2_OCP_V3_2_N
  \perst3#\  = RST_PERST3_OCP_V3_2_N
  \wake#\  = IRQ_LVC3_OCP_V3_2_WAKE_N
  RBT_ARB_IN  = OCP_V3_2_ISO1_RBT_ARB_IN
  RBT_ARB_OUT  = OCP_V3_2_ISO2_RBT_ARB_OUT
  SLOT_ID1  = OCP_V3_2_ID1
  RBT_TX_EN  = NCSI_OCP_V3_2_TX_EN
  RBT_TXD1  = NCSI_OCP_V3_2_TXD1
  RBT_TXD0  = NCSI_OCP_V3_2_TXD0
  GND_OA10  = GND
  REFCLKN3  = CLK_100M_OCP_V3_2_D_DN
  REFCLKP3  = CLK_100M_OCP_V3_2_D_DP
  GND_OA13  = GND
  RBT_CLK_IN  = CLK_50M_NCSI_OCP_V3_2_ISO
  NIC_PWR_GOOD  = FM_OCP_V3_2_PWR_GOOD
  MAIN_PWR_EN  = OCP_V3_2_MAIN_PWR_EN_R
  \ld#\  = SGPIO_OCP_V3_2_LD_N
  DATA_IN  = SGPIO_OCP_V3_2_DATAIN
  DATA_OUT  = SGPIO_OCP_V3_2_DATAOUT
  CLK  = SGPIO_OCP_V3_2_CLK
  SLOT_ID0  = OCP_V3_2_ID0
  RBT_RXD1  = NCSI_OCP_V3_2_RXD1
  RBT_RXD0  = NCSI_OCP_V3_2_RXD0
  GND_OB10  = GND
  REFCLKN2  = CLK_100M_OCP_V3_2_C_DN
  REFCLKP2  = CLK_100M_OCP_V3_2_C_DP
  GND_OB13  = GND
  RBT_CRS_DV  = NCSI_OCP_V3_2_CRS_DV

(kicad_pcb
	(version 20260206)
	(generator "pcbnew")
	(generator_version "10.0")
	(general
		(thickness 1.6)
		(legacy_teardrops no)
	)
	(paper "A4")
	(title_block
		(title "03242023_DA0F0TMBIJ0_F0T_Motherboard_J_brd_V01_OCP.brd")
		(comment 1 "Grand Teton / footprint 3456 of 6105 (J35), pads 45-88 of 175")
	)
	(layers
		(0 "F.Cu" signal "TOP")
		(4 "In1.Cu" signal "GND")
		(6 "In2.Cu" signal "IN1")
		(8 "In3.Cu" signal "GND1")
		(10 "In4.Cu" signal "IN2")
		(12 "In5.Cu" signal "GND2")
		(14 "In6.Cu" signal "IN3")
		(16 "In7.Cu" signal "GND3")
		(18 "In8.Cu" signal "VCC")
		(20 "In9.Cu" signal "VCC1")
		(22 "In10.Cu" signal "GND4")
		(24 "In11.Cu" signal "IN4")
		(26 "In12.Cu" signal "GND5")
		(28 "In13.Cu" signal "IN5")
		(30 "In14.Cu" signal "GND6")
		(32 "In15.Cu" signal "IN6")
		(34 "In16.Cu" signal "GND7")
		(2 "B.Cu" signal "BOTTOM")
		(9 "F.Adhes" user "F.Adhesive")
		(11 "B.Adhes" user "B.Adhesive")
		(13 "F.Paste" user "Package Geometry/Pastemask Top")
		(15 "B.Paste" user "Package Geometry/Pastemask Bottom")
		(5 "F.SilkS" user "Ref Des/Silkscreen Top")
		(7 "B.SilkS" user "Ref Des/Silkscreen Bottom")
		(1 "F.Mask" user "Board Geometry/Soldermask Top")
		(3 "B.Mask" user "Board Geometry/Soldermask Bottom")
		(17 "Dwgs.User" user "User.Drawings")
		(19 "Cmts.User" user "User.Comments")
		(21 "Eco1.User" user "User.Eco1")
		(23 "Eco2.User" user "User.Eco2")
		(25 "Edge.Cuts" user "Board Geometry/Outline")
		(27 "Margin" user)
		(31 "F.CrtYd" user "Package Geometry/Place Bound Top")
		(29 "B.CrtYd" user "Package Geometry/Place Bound Bottom")
		(35 "F.Fab" user "Ref Des/Assembly Top")
		(33 "B.Fab" user "Ref Des/Assembly Bottom")
	)
	(footprint ""
		(layer "F.Cu")
		(at 47.401988 -5.569966 -90)
		(property "Reference" "J35"
			(at -16.848074 29.242004 0)
			(unlocked yes)
			(layer "F.SilkS")
			(effects
				(font
					(size 0.7874 0.5842)
					(thickness 0.1524)
				)
				(justify left)
			)
		)
		(property "Value" ""
			(at 0 0 270)
			(layer "F.Fab")
			(effects
				(font
					(size 1.27 1.27)
				)
			)
		)
		(duplicate_pad_numbers_are_jumpers no)
		(pad "A43" smd rect
			(at -2.750058 14.454886 180)
			(size 0.381 1.4478)
			(layers "F.Cu" "F.Mask" "F.Paste")
			(net "GND")
		)
		(pad "A44" smd rect
			(at -2.750058 15.055088 180)
			(size 0.381 1.4478)
			(layers "F.Cu" "F.Mask" "F.Paste")
			(net "P5E_CPU1_PE1_RX_DN<8>")
		)
		(pad "A45" smd rect
			(at -2.750058 15.655036 180)
			(size 0.381 1.4478)
			(layers "F.Cu" "F.Mask" "F.Paste")
			(net "P5E_CPU1_PE1_RX_DP<8>")
		)
		(pad "A46" smd rect
			(at -2.750058 16.254984 180)
			(size 0.381 1.4478)
			(layers "F.Cu" "F.Mask" "F.Paste")
			(net "GND")
		)
		(pad "A47" smd rect
			(at -2.750058 16.854932 180)
			(size 0.381 1.4478)
			(layers "F.Cu" "F.Mask" "F.Paste")
			(net "P5E_CPU1_PE1_RX_DN<9>")
		)
		(pad "A48" smd rect
			(at -2.750058 17.45488 180)
			(size 0.381 1.4478)
			(layers "F.Cu" "F.Mask" "F.Paste")
			(net "P5E_CPU1_PE1_RX_DP<9>")
		)
		(pad "A49" smd rect
			(at -2.750058 18.055082 180)
			(size 0.381 1.4478)
			(layers "F.Cu" "F.Mask" "F.Paste")
			(net "GND")
		)
		(pad "A50" smd rect
			(at -2.750058 18.65503 180)
			(size 0.381 1.4478)
			(layers "F.Cu" "F.Mask" "F.Paste")
			(net "P5E_CPU1_PE1_RX_DN<10>")
		)
		(pad "A51" smd rect
			(at -2.750058 19.254978 180)
			(size 0.381 1.4478)
			(layers "F.Cu" "F.Mask" "F.Paste")
			(net "P5E_CPU1_PE1_RX_DP<10>")
		)
		(pad "A52" smd rect
			(at -2.750058 19.854926 180)
			(size 0.381 1.4478)
			(layers "F.Cu" "F.Mask" "F.Paste")
			(net "GND")
		)
		(pad "A53" smd rect
			(at -2.750058 20.455128 180)
			(size 0.381 1.4478)
			(layers "F.Cu" "F.Mask" "F.Paste")
			(net "P5E_CPU1_PE1_RX_DN<11>")
		)
		(pad "A54" smd rect
			(at -2.750058 21.055076 180)
			(size 0.381 1.4478)
			(layers "F.Cu" "F.Mask" "F.Paste")
			(net "P5E_CPU1_PE1_RX_DP<11>")
		)
		(pad "A55" smd rect
			(at -2.750058 21.655024 180)
			(size 0.381 1.4478)
			(layers "F.Cu" "F.Mask" "F.Paste")
			(net "GND")
		)
		(pad "A56" smd rect
			(at -2.750058 22.254972 180)
			(size 0.381 1.4478)
			(layers "F.Cu" "F.Mask" "F.Paste")
			(net "P5E_CPU1_PE1_RX_DN<12>")
		)
		(pad "A57" smd rect
			(at -2.750058 22.85492 180)
			(size 0.381 1.4478)
			(layers "F.Cu" "F.Mask" "F.Paste")
			(net "P5E_CPU1_PE1_RX_DP<12>")
		)
		(pad "A58" smd rect
			(at -2.750058 23.455122 180)
			(size 0.381 1.4478)
			(layers "F.Cu" "F.Mask" "F.Paste")
			(net "GND")
		)
		(pad "A59" smd rect
			(at -2.750058 24.05507 180)
			(size 0.381 1.4478)
			(layers "F.Cu" "F.Mask" "F.Paste")
			(net "P5E_CPU1_PE1_RX_DN<13>")
		)
		(pad "A60" smd rect
			(at -2.750058 24.655018 180)
			(size 0.381 1.4478)
			(layers "F.Cu" "F.Mask" "F.Paste")
			(net "P5E_CPU1_PE1_RX_DP<13>")
		)
		(pad "A61" smd rect
			(at -2.750058 25.254966 180)
			(size 0.381 1.4478)
			(layers "F.Cu" "F.Mask" "F.Paste")
			(net "GND")
		)
		(pad "A62" smd rect
			(at -2.750058 25.854914 180)
			(size 0.381 1.4478)
			(layers "F.Cu" "F.Mask" "F.Paste")
			(net "P5E_CPU1_PE1_RX_DN<14>")
		)
		(pad "A63" smd rect
			(at -2.750058 26.455116 180)
			(size 0.381 1.4478)
			(layers "F.Cu" "F.Mask" "F.Paste")
			(net "P5E_CPU1_PE1_RX_DP<14>")
		)
		(pad "A64" smd rect
			(at -2.750058 27.055064 180)
			(size 0.381 1.4478)
			(layers "F.Cu" "F.Mask" "F.Paste")
			(net "GND")
		)
		(pad "A65" smd rect
			(at -2.750058 27.655012 180)
			(size 0.381 1.4478)
			(layers "F.Cu" "F.Mask" "F.Paste")
			(net "P5E_CPU1_PE1_RX_DN<15>")
		)
		(pad "A66" smd rect
			(at -2.750058 28.25496 180)
			(size 0.381 1.4478)
			(layers "F.Cu" "F.Mask" "F.Paste")
			(net "P5E_CPU1_PE1_RX_DP<15>")
		)
		(pad "A67" smd rect
			(at -2.750058 28.854908 180)
			(size 0.381 1.4478)
			(layers "F.Cu" "F.Mask" "F.Paste")
			(net "GND")
		)
		(pad "A68" smd rect
			(at -2.750058 29.45511 180)
			(size 0.381 1.4478)
			(layers "F.Cu" "F.Mask" "F.Paste")
			(net "USB2_5_R1_DN")
		)
		(pad "A69" smd rect
			(at -2.750058 30.055058 180)
			(size 0.381 1.4478)
			(layers "F.Cu" "F.Mask" "F.Paste")
			(net "USB2_5_R1_DP")
		)
		(pad "A70" smd rect
			(at -2.750058 30.655006 180)
			(size 0.381 1.4478)
			(layers "F.Cu" "F.Mask" "F.Paste")
			(net "OCP_V3_2_PWRBRK_N")
		)
		(pad "B1" smd rect
			(at -5.700014 -18.465038 180)
			(size 0.381 1.4478)
			(layers "F.Cu" "F.Mask" "F.Paste")
			(net "P12V_OCP_V3_2")
		)
		(pad "B2" smd rect
			(at -5.700014 -17.86509 180)
			(size 0.381 1.4478)
			(layers "F.Cu" "F.Mask" "F.Paste")
			(net "P12V_OCP_V3_2")
		)
		(pad "B3" smd rect
			(at -5.700014 -17.264888 180)
			(size 0.381 1.4478)
			(layers "F.Cu" "F.Mask" "F.Paste")
			(net "P12V_OCP_V3_2")
		)
		(pad "B4" smd rect
			(at -5.700014 -16.66494 180)
			(size 0.381 1.4478)
			(layers "F.Cu" "F.Mask" "F.Paste")
			(net "P12V_OCP_V3_2")
		)
		(pad "B5" smd rect
			(at -5.700014 -16.064992 180)
			(size 0.381 1.4478)
			(layers "F.Cu" "F.Mask" "F.Paste")
			(net "P12V_OCP_V3_2")
		)
		(pad "B6" smd rect
			(at -5.700014 -15.465044 180)
			(size 0.381 1.4478)
			(layers "F.Cu" "F.Mask" "F.Paste")
			(net "P12V_OCP_V3_2")
		)
		(pad "B7" smd rect
			(at -5.700014 -14.865096 180)
			(size 0.381 1.4478)
			(layers "F.Cu" "F.Mask" "F.Paste")
			(net "OCP_V3_2_BIF0_R_N")
		)
		(pad "B8" smd rect
			(at -5.700014 -14.264894 180)
			(size 0.381 1.4478)
			(layers "F.Cu" "F.Mask" "F.Paste")
			(net "OCP_V3_2_BIF1_R_N")
		)
		(pad "B9" smd rect
			(at -5.700014 -13.664946 180)
			(size 0.381 1.4478)
			(layers "F.Cu" "F.Mask" "F.Paste")
			(net "OCP_V3_2_BIF2_R_N")
		)
		(pad "B10" smd rect
			(at -5.700014 -13.064998 180)
			(size 0.381 1.4478)
			(layers "F.Cu" "F.Mask" "F.Paste")
			(net "RST_PERST0_OCP_V3_2_N")
		)
		(pad "B11" smd rect
			(at -5.700014 -12.46505 180)
			(size 0.381 1.4478)
			(layers "F.Cu" "F.Mask" "F.Paste")
			(net "P3V3_OCP_V3_2")
		)
		(pad "B12" smd rect
			(at -5.700014 -11.865102 180)
			(size 0.381 1.4478)
			(layers "F.Cu" "F.Mask" "F.Paste")
			(net "OCP_V3_2_AUX_PWR_EN_R")
		)
		(pad "B13" smd rect
			(at -5.700014 -11.2649 180)
			(size 0.381 1.4478)
			(layers "F.Cu" "F.Mask" "F.Paste")
			(net "GND")
		)
		(pad "B14" smd rect
			(at -5.700014 -10.664952 180)
			(size 0.381 1.4478)
			(layers "F.Cu" "F.Mask" "F.Paste")
			(net "CLK_100M_OCP_V3_2_A_DN")
		)
		(pad "B15" smd rect
			(at -5.700014 -10.065004 180)
			(size 0.381 1.4478)
			(layers "F.Cu" "F.Mask" "F.Paste")
			(net "CLK_100M_OCP_V3_2_A_DP")
		)
		(pad "B16" smd rect
			(at -5.700014 -9.465056 180)
			(size 0.381 1.4478)
			(layers "F.Cu" "F.Mask" "F.Paste")
			(net "GND")
		)
	)
)
